FILE_TYPE = CONNECTIVITY;
{Allegro Design Entry HDL 17.2-2016 S081 (4005846) 1/11/2022}
"PAGE_NUMBER" = 215;
0"NC";
1"GND\g";
2"GND\g";
3"SMB_HOST_ME_SDA"CDS_PHYS_NET_NAME"SMB_FRU_U181_3V3AUX_SDA_R";
4"PWRGD_PS_PWROK_ME_CONN"CDS_PHYS_NET_NAME"SMB_FRU_U181_3V3AUX_SDA_R";
5"PECI_BMC_ME"CDS_PHYS_NET_NAME"SMB_FRU_U181_3V3AUX_SDA_R";
6"IRQ_SML0_ALERT_R1_N"CDS_PHYS_NET_NAME"SMB_FRU_U181_3V3AUX_SDA_R";
7"IRQ_SML1_PMBUS_ALERT_R_N"CDS_PHYS_NET_NAME"SMB_FRU_U181_3V3AUX_SDA";
8"SMB_HOST_3V3AUX_SCL_R5";
9"IRQ_SML1_PMBUS_ALERT_N"CDS_PHYS_NET_NAME"SMB_FRU_U181_3V3AUX_SDA_R";
10"SMB_SML0_ME_SCL"CDS_PHYS_NET_NAME"SMB_FRU_U181_3V3AUX_SDA_R";
11"SMB_SML0_ME_SDA"CDS_PHYS_NET_NAME"SMB_FRU_U181_3V3AUX_SDA_R";
12"SMB_PMBUS_SML1_ME_SCL"CDS_PHYS_NET_NAME"SMB_FRU_U181_3V3AUX_SDA_R";
13"SMB_PMBUS_SML1_ME_SDA"CDS_PHYS_NET_NAME"SMB_FRU_U181_3V3AUX_SDA_R";
14"RST_RSMRST_NM_HDR_N"CDS_PHYS_NET_NAME"SMB_FRU_U181_3V3AUX_SDA_R";
15"IRQ_SML0_ALERT_R1_N"CDS_PHYS_NET_NAME"SMB_FRU_U181_3V3AUX_SDA_R";
16"IRQ_SML1_PMBUS_ALERT_R_N"CDS_PHYS_NET_NAME"SMB_FRU_U181_3V3AUX_SDA_R";
17"FM_BIOS_POST_CMPLT_HDR_N"CDS_PHYS_NET_NAME"SMB_FRU_U181_3V3AUX_SDA_R";
18"SMB_HOST_ME_SCL"CDS_PHYS_NET_NAME"SMB_FRU_U181_3V3AUX_SDA_R";
19"IRQ_SML0_ALERT_R_N"CDS_PHYS_NET_NAME"SMB_FRU_U181_3V3AUX_SDA";
20"SMB_HOST_ME_SCL";
21"SMB_HOST_ME_SDA";
22"SMB_HOST_3V3AUX_SDA_R5";
23"PWRGD_PS_PWROK"CDS_PHYS_NET_NAME"SMB_FRU_U181_3V3AUX_SDA_R";
%"Q_RES"
"1","(-1400,1725)","0","pure_quanta","I12";
;
PART_NUMBER"CS03322FB03"
VALUE"33.2"
TOLERANCE"1%"
MATERIAL"CHIP"
$LOCATION"R3053"
PACK_TYPE"0402LF"
CDS_LIB"pure_quanta"
WATTAGE"1/16W"
CDS_LOCATION"R3053"
$SEC"1"
CDS_SEC"1";
"B"
$PN"2"21;
"A"
$PN"1"22;
%"Q_RES"
"1","(-1400,1925)","0","pure_quanta","I13";
;
PART_NUMBER"CS03322FB03"
WATTAGE"1/16W"
VALUE"33.2"
MATERIAL"CHIP"
TOLERANCE"1%"
PACK_TYPE"0402LF"
$LOCATION"R3052"
CDS_LIB"pure_quanta"
CDS_LOCATION"R3052"
$SEC"1"
CDS_SEC"1";
"B"
$PN"2"20;
"A"
$PN"1"8;
%"Q_RES"
"1","(-1400,2150)","0","pure_quanta","I2";
;
PART_NUMBER"CS00002JB13"
VALUE"0"
TOLERANCE"5%"
MATERIAL"CHIP"
$LOCATION"R3051"
WATTAGE"1/16W"
PACK_TYPE"0402LF"
CDS_LIB"pure_quanta"
CDS_LOCATION"R3051"
$SEC"1"
CDS_SEC"1";
"B"
$PN"2"9;
"A"
$PN"1"7;
%"UNIVERSAL_GND"
"1","(-1900,2800)","0","logical_power","I21";
;
CDS_LIB"logical_power"
HDL_POWER"GND";
"A"2;
%"Q_RES"
"1","(-125,3100)","0","pure_quanta","I23";
;
PART_NUMBER"CS03322FB03"
TOLERANCE"1%"
VALUE"33.2"
MATERIAL"CHIP"
$LOCATION"R3054"
WATTAGE"1/16W"
PACK_TYPE"0402LF"
CDS_LIB"pure_quanta"
CDS_LOCATION"R3054"
$SEC"1"
CDS_SEC"1";
"B"
$PN"2"23;
"A"
$PN"1"4;
%"UNIVERSAL_GND"
"1","(-1150,2800)","0","logical_power","I27";
;
HDL_POWER"GND"
CDS_LIB"logical_power";
"A"1;
%"Q_RES"
"1","(-1400,2325)","0","pure_quanta","I28";
;
PART_NUMBER"CS00002JB13"
VALUE"0"
MATERIAL"CHIP"
TOLERANCE"5%"
$LOCATION"R3103"
CDS_LIB"pure_quanta"
PACK_TYPE"0402LF"
WATTAGE"1/16W"
CDS_LOCATION"R3103"
$SEC"1"
CDS_SEC"1";
"B"
$PN"2"6;
"A"
$PN"1"19;
%"SCONN20_513860200CV01"
"1","(-1525,3275)","0","pure_quanta","I32";
;
PART_NUMBER"DFHD20MS193"
PART_TYPE"SMLF"
MATERIAL"IO"
VALUE"SCONN20_51386-0200C-V01"
LOCATION"J100"
CDS_LMAN_SYM_OUTLINE"-150,275,150,-275"
NEEDS_NO_SIZE"TRUE"
CDS_LIB"pure_quanta"
$SEC"1"
CDS_SEC"1";
"20"
$PN"20"0;
"19"
$PN"19"17;
"18"
$PN"18"4;
"17"
$PN"17"2;
"16"
$PN"16"5;
"15"
$PN"15"2;
"14"
$PN"14"0;
"13"
$PN"13"3;
"12"
$PN"12"1;
"11"
$PN"11"18;
"10"
$PN"10"1;
"9"
$PN"9"14;
"8"
$PN"8"16;
"7"
$PN"7"13;
"6"
$PN"6"1;
"5"
$PN"5"12;
"4"
$PN"4"15;
"3"
$PN"3"11;
"2"
$PN"2"1;
"1"
$PN"1"10;
END.
